(kicad_pcb
	(version 20260206)
	(generator "pcbnew")
	(generator_version "10.0")
	(general
		(thickness 1.6)
		(legacy_teardrops no)
	)
	(paper "A4")
	(title_block
		(title "01162023_DA0F0TEBIF0_F0T_Expander_BD_F_brd_V02_OCP.brd")
		(comment 1 "Grand Teton / footprints 1238-1244 of 9728")
	)
	(layers
		(0 "F.Cu" signal "TOP")
		(4 "In1.Cu" signal "GND")
		(6 "In2.Cu" signal "VCC")
		(8 "In3.Cu" signal "VCC1")
		(10 "In4.Cu" signal "GND1")
		(12 "In5.Cu" signal "IN1")
		(14 "In6.Cu" signal "GND2")
		(16 "In7.Cu" signal "IN2")
		(18 "In8.Cu" signal "GND3")
		(20 "In9.Cu" signal "IN3")
		(22 "In10.Cu" signal "GND4")
		(24 "In11.Cu" signal "IN4")
		(26 "In12.Cu" signal "GND5")
		(28 "In13.Cu" signal "IN5")
		(30 "In14.Cu" signal "GND6")
		(32 "In15.Cu" signal "IN6")
		(34 "In16.Cu" signal "GND7")
		(2 "B.Cu" signal "BOTTOM")
		(9 "F.Adhes" user "F.Adhesive")
		(11 "B.Adhes" user "B.Adhesive")
		(13 "F.Paste" user "Package Geometry/Pastemask Top")
		(15 "B.Paste" user "Package Geometry/Pastemask Bottom")
		(5 "F.SilkS" user "Ref Des/Silkscreen Top")
		(7 "B.SilkS" user "Ref Des/Silkscreen Bottom")
		(1 "F.Mask" user "Board Geometry/Soldermask Top")
		(3 "B.Mask" user "Board Geometry/Soldermask Bottom")
		(17 "Dwgs.User" user "User.Drawings")
		(19 "Cmts.User" user "User.Comments")
		(21 "Eco1.User" user "User.Eco1")
		(23 "Eco2.User" user "User.Eco2")
		(25 "Edge.Cuts" user "Board Geometry/Outline")
		(27 "Margin" user)
		(31 "F.CrtYd" user "Package Geometry/Place Bound Top")
		(29 "B.CrtYd" user "Package Geometry/Place Bound Bottom")
		(35 "F.Fab" user "Ref Des/Assembly Top")
		(33 "B.Fab" user "Ref Des/Assembly Bottom")
	)
	(footprint ""
		(layer "F.Cu")
		(at 309.307484 -81.09966)
		(property "Reference" "Q6"
			(at -0.849884 1.80213 0)
			(unlocked yes)
			(layer "F.SilkS")
			(effects
				(font
					(size 0.7874 0.5842)
					(thickness 0.1524)
				)
				(justify left)
			)
		)
		(property "Value" ""
			(at 0 0 0)
			(layer "F.Fab")
			(effects
				(font
					(size 1.27 1.27)
				)
			)
		)
		(duplicate_pad_numbers_are_jumpers no)
		(fp_line
			(start -1.38176 -1.100074)
			(end -1.38176 1.100074)
			(stroke
				(width 0.1524)
				(type default)
			)
			(layer "F.SilkS")
		)
		(fp_line
			(start -1.38176 1.100074)
			(end 1.38176 1.100074)
			(stroke
				(width 0.1524)
				(type default)
			)
			(layer "F.SilkS")
		)
		(fp_line
			(start -0.592074 -1.100074)
			(end -1.38176 -1.100074)
			(stroke
				(width 0.1524)
				(type default)
			)
			(layer "F.SilkS")
		)
		(fp_line
			(start 0 -0.508)
			(end -0.592074 -1.100074)
			(stroke
				(width 0.1524)
				(type default)
			)
			(layer "F.SilkS")
		)
		(fp_line
			(start 0.592074 -1.100074)
			(end 0 -0.508)
			(stroke
				(width 0.1524)
				(type default)
			)
			(layer "F.SilkS")
		)
		(fp_line
			(start 1.38176 -1.100074)
			(end 0.592074 -1.100074)
			(stroke
				(width 0.1524)
				(type default)
			)
			(layer "F.SilkS")
		)
		(fp_line
			(start 1.38176 1.100074)
			(end 1.38176 -1.100074)
			(stroke
				(width 0.1524)
				(type default)
			)
			(layer "F.SilkS")
		)
		(fp_poly
			(pts
				(xy -1.9431 -0.870204) (xy -1.50241 -0.649986) (xy -1.9431 -0.429768)
			)
			(stroke
				(width 0)
				(type default)
			)
			(fill yes)
			(layer "F.SilkS")
		)
		(fp_line
			(start -0.674878 -1.100074)
			(end -0.674878 1.100074)
			(stroke
				(width 0.1)
				(type default)
			)
			(layer "F.Fab")
		)
		(fp_line
			(start -0.674878 1.100074)
			(end 0.674878 1.100074)
			(stroke
				(width 0.1)
				(type default)
			)
			(layer "F.Fab")
		)
		(fp_line
			(start 0.674878 -1.100074)
			(end -0.674878 -1.100074)
			(stroke
				(width 0.1)
				(type default)
			)
			(layer "F.Fab")
		)
		(fp_line
			(start 0.674878 1.100074)
			(end 0.674878 -1.100074)
			(stroke
				(width 0.1)
				(type default)
			)
			(layer "F.Fab")
		)
		(fp_poly
			(pts
				(xy -1.9431 -0.870204) (xy -1.50241 -0.649986) (xy -1.9431 -0.429768)
			)
			(stroke
				(width 0)
				(type default)
			)
			(fill yes)
			(layer "F.Fab")
		)
		(pad "1" smd rect
			(at -0.94996 -0.649986 270)
			(size 0.4318 0.6096)
			(layers "F.Cu" "F.Mask" "F.Paste")
			(net "GND")
		)
		(pad "2" smd rect
			(at -0.94996 0 270)
			(size 0.4318 0.6096)
			(layers "F.Cu" "F.Mask" "F.Paste")
			(net "HP_NIC5_HSC_PWRGD_N")
		)
		(pad "3" smd rect
			(at -0.94996 0.649986 270)
			(size 0.4318 0.6096)
			(layers "F.Cu" "F.Mask" "F.Paste")
			(net "HP_NIC5_HSC_PWRGD_N")
		)
		(pad "4" smd rect
			(at 0.94996 0.649986 270)
			(size 0.4318 0.6096)
			(layers "F.Cu" "F.Mask" "F.Paste")
			(net "GND")
		)
		(pad "5" smd rect
			(at 0.94996 0 270)
			(size 0.4318 0.6096)
			(layers "F.Cu" "F.Mask" "F.Paste")
			(net "PWRGD_P12V_NIC5_R")
		)
		(pad "6" smd rect
			(at 0.94996 -0.649986 270)
			(size 0.4318 0.6096)
			(layers "F.Cu" "F.Mask" "F.Paste")
			(net "HP_NIC5_PWRGD_R")
		)
	)
	(footprint ""
		(layer "F.Cu")
		(at 265.487658 -294.819832)
		(property "Reference" "C3375"
			(at 0 0 0)
			(layer "F.SilkS")
			(hide yes)
			(effects
				(font
					(size 1.27 1.27)
				)
			)
		)
		(property "Value" ""
			(at 0 0 0)
			(layer "F.Fab")
			(effects
				(font
					(size 1.27 1.27)
				)
			)
		)
		(duplicate_pad_numbers_are_jumpers no)
		(fp_line
			(start -1.2954 -0.5842)
			(end 1.2954 -0.5842)
			(stroke
				(width 0.1524)
				(type default)
			)
			(layer "F.SilkS")
		)
		(fp_line
			(start -1.2954 0.5842)
			(end -1.2954 -0.5842)
			(stroke
				(width 0.1524)
				(type default)
			)
			(layer "F.SilkS")
		)
		(fp_line
			(start 1.2954 -0.5842)
			(end 1.2954 0.5842)
			(stroke
				(width 0.1524)
				(type default)
			)
			(layer "F.SilkS")
		)
		(fp_line
			(start 1.2954 0.5842)
			(end -1.2954 0.5842)
			(stroke
				(width 0.1524)
				(type default)
			)
			(layer "F.SilkS")
		)
		(fp_line
			(start -1.1938 -0.4064)
			(end -0.8636 -0.4064)
			(stroke
				(width 0.1)
				(type default)
			)
			(layer "F.Fab")
		)
		(fp_line
			(start -1.1938 0.4064)
			(end -1.1938 -0.4064)
			(stroke
				(width 0.1)
				(type default)
			)
			(layer "F.Fab")
		)
		(fp_line
			(start -0.8636 -0.4572)
			(end 0.8636 -0.4572)
			(stroke
				(width 0.1)
				(type default)
			)
			(layer "F.Fab")
		)
		(fp_line
			(start -0.8636 -0.4064)
			(end -0.8636 -0.4572)
			(stroke
				(width 0.1)
				(type default)
			)
			(layer "F.Fab")
		)
		(fp_line
			(start -0.8636 0.4064)
			(end -1.1938 0.4064)
			(stroke
				(width 0.1)
				(type default)
			)
			(layer "F.Fab")
		)
		(fp_line
			(start -0.8636 0.4572)
			(end -0.8636 0.4064)
			(stroke
				(width 0.1)
				(type default)
			)
			(layer "F.Fab")
		)
		(fp_line
			(start 0.8636 -0.4572)
			(end 0.8636 -0.4064)
			(stroke
				(width 0.1)
				(type default)
			)
			(layer "F.Fab")
		)
		(fp_line
			(start 0.8636 -0.4064)
			(end 1.1938 -0.4064)
			(stroke
				(width 0.1)
				(type default)
			)
			(layer "F.Fab")
		)
		(fp_line
			(start 0.8636 0.4064)
			(end 0.8636 0.4572)
			(stroke
				(width 0.1)
				(type default)
			)
			(layer "F.Fab")
		)
		(fp_line
			(start 0.8636 0.4572)
			(end -0.8636 0.4572)
			(stroke
				(width 0.1)
				(type default)
			)
			(layer "F.Fab")
		)
		(fp_line
			(start 1.1938 -0.4064)
			(end 1.1938 0.4064)
			(stroke
				(width 0.1)
				(type default)
			)
			(layer "F.Fab")
		)
		(fp_line
			(start 1.1938 0.4064)
			(end 0.8636 0.4064)
			(stroke
				(width 0.1)
				(type default)
			)
			(layer "F.Fab")
		)
		(pad "1" smd rect
			(at -0.7366 0 270)
			(size 0.7112 0.8128)
			(layers "F.Cu" "F.Mask" "F.Paste")
			(net "PCEPLL2_VDDA18_PEX2")
		)
		(pad "2" smd rect
			(at 0.7366 0 270)
			(size 0.7112 0.8128)
			(layers "F.Cu" "F.Mask" "F.Paste")
			(net "GND")
		)
	)
	(footprint ""
		(layer "F.Cu")
		(at 173.75632 -61.487812 180)
		(property "Reference" "R5982"
			(at 0 0 180)
			(layer "F.SilkS")
			(hide yes)
			(effects
				(font
					(size 1.27 1.27)
				)
			)
		)
		(property "Value" ""
			(at 0 0 180)
			(layer "F.Fab")
			(effects
				(font
					(size 1.27 1.27)
				)
			)
		)
		(duplicate_pad_numbers_are_jumpers no)
		(fp_line
			(start 0.7874 0.4064)
			(end -0.7874 0.4064)
			(stroke
				(width 0.1524)
				(type default)
			)
			(layer "F.SilkS")
		)
		(fp_line
			(start 0.7874 -0.4064)
			(end 0.7874 0.4064)
			(stroke
				(width 0.1524)
				(type default)
			)
			(layer "F.SilkS")
		)
		(fp_line
			(start -0.7874 0.4064)
			(end -0.7874 -0.4064)
			(stroke
				(width 0.1524)
				(type default)
			)
			(layer "F.SilkS")
		)
		(fp_line
			(start -0.7874 -0.4064)
			(end 0.7874 -0.4064)
			(stroke
				(width 0.1524)
				(type default)
			)
			(layer "F.SilkS")
		)
		(fp_line
			(start 0.67945 0.3048)
			(end 0.120396 0.3048)
			(stroke
				(width 0.1)
				(type default)
			)
			(layer "F.Fab")
		)
		(fp_line
			(start 0.67945 -0.3048)
			(end 0.67945 0.3048)
			(stroke
				(width 0.1)
				(type default)
			)
			(layer "F.Fab")
		)
		(fp_line
			(start 0.12065 -0.2794)
			(end 0.12065 -0.3048)
			(stroke
				(width 0.1)
				(type default)
			)
			(layer "F.Fab")
		)
		(fp_line
			(start 0.12065 -0.3048)
			(end 0.67945 -0.3048)
			(stroke
				(width 0.1)
				(type default)
			)
			(layer "F.Fab")
		)
		(fp_line
			(start 0.120396 0.3048)
			(end 0.120396 0.2794)
			(stroke
				(width 0.1)
				(type default)
			)
			(layer "F.Fab")
		)
		(fp_line
			(start 0.120396 0.2794)
			(end -0.12065 0.2794)
			(stroke
				(width 0.1)
				(type default)
			)
			(layer "F.Fab")
		)
		(fp_line
			(start -0.12065 0.3048)
			(end -0.67945 0.3048)
			(stroke
				(width 0.1)
				(type default)
			)
			(layer "F.Fab")
		)
		(fp_line
			(start -0.12065 0.2794)
			(end -0.12065 0.3048)
			(stroke
				(width 0.1)
				(type default)
			)
			(layer "F.Fab")
		)
		(fp_line
			(start -0.12065 -0.2794)
			(end 0.12065 -0.2794)
			(stroke
				(width 0.1)
				(type default)
			)
			(layer "F.Fab")
		)
		(fp_line
			(start -0.12065 -0.305054)
			(end -0.12065 -0.2794)
			(stroke
				(width 0.1)
				(type default)
			)
			(layer "F.Fab")
		)
		(fp_line
			(start -0.67945 0.3048)
			(end -0.67945 -0.305054)
			(stroke
				(width 0.1)
				(type default)
			)
			(layer "F.Fab")
		)
		(fp_line
			(start -0.67945 -0.305054)
			(end -0.12065 -0.305054)
			(stroke
				(width 0.1)
				(type default)
			)
			(layer "F.Fab")
		)
		(pad "1" smd circle
			(at -0.40005 0 180)
			(size 0 0)
			(layers "F.Cu" "F.Mask" "F.Paste")
			(net "P3V3_AUX")
		)
		(pad "2" smd circle
			(at 0.40005 0 180)
			(size 0 0)
			(layers "F.Cu" "F.Mask" "F.Paste")
			(net "PWRGD_P12V_SSD6_D")
		)
	)
	(footprint ""
		(layer "F.Cu")
		(at 124.14123 -172.444918 90)
		(property "Reference" "C4500"
			(at 0 0 90)
			(layer "F.SilkS")
			(hide yes)
			(effects
				(font
					(size 1.27 1.27)
				)
			)
		)
		(property "Value" ""
			(at 0 0 90)
			(layer "F.Fab")
			(effects
				(font
					(size 1.27 1.27)
				)
			)
		)
		(duplicate_pad_numbers_are_jumpers no)
		(fp_line
			(start 0.7874 -0.4064)
			(end 0.7874 0.4064)
			(stroke
				(width 0.1524)
				(type default)
			)
			(layer "F.SilkS")
		)
		(fp_line
			(start -0.7874 -0.4064)
			(end 0.7874 -0.4064)
			(stroke
				(width 0.1524)
				(type default)
			)
			(layer "F.SilkS")
		)
		(fp_line
			(start 0.7874 0.4064)
			(end -0.7874 0.4064)
			(stroke
				(width 0.1524)
				(type default)
			)
			(layer "F.SilkS")
		)
		(fp_line
			(start -0.7874 0.4064)
			(end -0.7874 -0.4064)
			(stroke
				(width 0.1524)
				(type default)
			)
			(layer "F.SilkS")
		)
		(fp_line
			(start -0.12065 -0.305054)
			(end -0.12065 -0.2794)
			(stroke
				(width 0.1)
				(type default)
			)
			(layer "F.Fab")
		)
		(fp_line
			(start -0.67945 -0.305054)
			(end -0.12065 -0.305054)
			(stroke
				(width 0.1)
				(type default)
			)
			(layer "F.Fab")
		)
		(fp_line
			(start 0.67945 -0.3048)
			(end 0.67945 0.3048)
			(stroke
				(width 0.1)
				(type default)
			)
			(layer "F.Fab")
		)
		(fp_line
			(start 0.12065 -0.3048)
			(end 0.67945 -0.3048)
			(stroke
				(width 0.1)
				(type default)
			)
			(layer "F.Fab")
		)
		(fp_line
			(start 0.12065 -0.2794)
			(end 0.12065 -0.3048)
			(stroke
				(width 0.1)
				(type default)
			)
			(layer "F.Fab")
		)
		(fp_line
			(start -0.12065 -0.2794)
			(end 0.12065 -0.2794)
			(stroke
				(width 0.1)
				(type default)
			)
			(layer "F.Fab")
		)
		(fp_line
			(start 0.120396 0.2794)
			(end -0.12065 0.2794)
			(stroke
				(width 0.1)
				(type default)
			)
			(layer "F.Fab")
		)
		(fp_line
			(start -0.12065 0.2794)
			(end -0.12065 0.3048)
			(stroke
				(width 0.1)
				(type default)
			)
			(layer "F.Fab")
		)
		(fp_line
			(start 0.67945 0.3048)
			(end 0.120396 0.3048)
			(stroke
				(width 0.1)
				(type default)
			)
			(layer "F.Fab")
		)
		(fp_line
			(start 0.120396 0.3048)
			(end 0.120396 0.2794)
			(stroke
				(width 0.1)
				(type default)
			)
			(layer "F.Fab")
		)
		(fp_line
			(start -0.12065 0.3048)
			(end -0.67945 0.3048)
			(stroke
				(width 0.1)
				(type default)
			)
			(layer "F.Fab")
		)
		(fp_line
			(start -0.67945 0.3048)
			(end -0.67945 -0.305054)
			(stroke
				(width 0.1)
				(type default)
			)
			(layer "F.Fab")
		)
		(pad "1" smd circle
			(at -0.40005 0 90)
			(size 0 0)
			(layers "F.Cu" "F.Mask" "F.Paste")
			(net "NIC1_CLK_EN_R_N")
		)
		(pad "2" smd circle
			(at 0.40005 0 90)
			(size 0 0)
			(layers "F.Cu" "F.Mask" "F.Paste")
			(net "GND")
		)
	)
	(footprint ""
		(layer "F.Cu")
		(at 136.445244 -87.813642 180)
		(property "Reference" "R1576"
			(at 0 0 180)
			(layer "F.SilkS")
			(hide yes)
			(effects
				(font
					(size 1.27 1.27)
				)
			)
		)
		(property "Value" ""
			(at 0 0 180)
			(layer "F.Fab")
			(effects
				(font
					(size 1.27 1.27)
				)
			)
		)
		(duplicate_pad_numbers_are_jumpers no)
		(fp_line
			(start 0.7874 0.4064)
			(end -0.7874 0.4064)
			(stroke
				(width 0.1524)
				(type default)
			)
			(layer "F.SilkS")
		)
		(fp_line
			(start 0.7874 -0.4064)
			(end 0.7874 0.4064)
			(stroke
				(width 0.1524)
				(type default)
			)
			(layer "F.SilkS")
		)
		(fp_line
			(start -0.7874 0.4064)
			(end -0.7874 -0.4064)
			(stroke
				(width 0.1524)
				(type default)
			)
			(layer "F.SilkS")
		)
		(fp_line
			(start -0.7874 -0.4064)
			(end 0.7874 -0.4064)
			(stroke
				(width 0.1524)
				(type default)
			)
			(layer "F.SilkS")
		)
		(fp_line
			(start 0.67945 0.3048)
			(end 0.120396 0.3048)
			(stroke
				(width 0.1)
				(type default)
			)
			(layer "F.Fab")
		)
		(fp_line
			(start 0.67945 -0.3048)
			(end 0.67945 0.3048)
			(stroke
				(width 0.1)
				(type default)
			)
			(layer "F.Fab")
		)
		(fp_line
			(start 0.12065 -0.2794)
			(end 0.12065 -0.3048)
			(stroke
				(width 0.1)
				(type default)
			)
			(layer "F.Fab")
		)
		(fp_line
			(start 0.12065 -0.3048)
			(end 0.67945 -0.3048)
			(stroke
				(width 0.1)
				(type default)
			)
			(layer "F.Fab")
		)
		(fp_line
			(start 0.120396 0.3048)
			(end 0.120396 0.2794)
			(stroke
				(width 0.1)
				(type default)
			)
			(layer "F.Fab")
		)
		(fp_line
			(start 0.120396 0.2794)
			(end -0.12065 0.2794)
			(stroke
				(width 0.1)
				(type default)
			)
			(layer "F.Fab")
		)
		(fp_line
			(start -0.12065 0.3048)
			(end -0.67945 0.3048)
			(stroke
				(width 0.1)
				(type default)
			)
			(layer "F.Fab")
		)
		(fp_line
			(start -0.12065 0.2794)
			(end -0.12065 0.3048)
			(stroke
				(width 0.1)
				(type default)
			)
			(layer "F.Fab")
		)
		(fp_line
			(start -0.12065 -0.2794)
			(end 0.12065 -0.2794)
			(stroke
				(width 0.1)
				(type default)
			)
			(layer "F.Fab")
		)
		(fp_line
			(start -0.12065 -0.305054)
			(end -0.12065 -0.2794)
			(stroke
				(width 0.1)
				(type default)
			)
			(layer "F.Fab")
		)
		(fp_line
			(start -0.67945 0.3048)
			(end -0.67945 -0.305054)
			(stroke
				(width 0.1)
				(type default)
			)
			(layer "F.Fab")
		)
		(fp_line
			(start -0.67945 -0.305054)
			(end -0.12065 -0.305054)
			(stroke
				(width 0.1)
				(type default)
			)
			(layer "F.Fab")
		)
		(pad "1" smd circle
			(at -0.40005 0 180)
			(size 0 0)
			(layers "F.Cu" "F.Mask" "F.Paste")
			(net "SMB_BIC_I2C9_MUX0_SSD4_R_SDA")
		)
		(pad "2" smd circle
			(at 0.40005 0 180)
			(size 0 0)
			(layers "F.Cu" "F.Mask" "F.Paste")
			(net "SMB_BIC_I2C9_MUX0_SSD4_SDA")
		)
	)
	(footprint ""
		(layer "F.Cu")
		(at 268.838426 -134.008876)
		(property "Reference" "C457"
			(at 0 0 0)
			(layer "F.SilkS")
			(hide yes)
			(effects
				(font
					(size 1.27 1.27)
				)
			)
		)
		(property "Value" ""
			(at 0 0 0)
			(layer "F.Fab")
			(effects
				(font
					(size 1.27 1.27)
				)
			)
		)
		(duplicate_pad_numbers_are_jumpers no)
		(fp_line
			(start -0.299974 -0.150114)
			(end 0.299974 -0.150114)
			(stroke
				(width 0.1)
				(type default)
			)
			(layer "F.Fab")
		)
		(fp_line
			(start -0.299974 0.150114)
			(end -0.299974 -0.150114)
			(stroke
				(width 0.1)
				(type default)
			)
			(layer "F.Fab")
		)
		(fp_line
			(start 0.299974 -0.150114)
			(end 0.299974 0.150114)
			(stroke
				(width 0.1)
				(type default)
			)
			(layer "F.Fab")
		)
		(fp_line
			(start 0.299974 0.150114)
			(end -0.299974 0.150114)
			(stroke
				(width 0.1)
				(type default)
			)
			(layer "F.Fab")
		)
		(pad "1" smd rect
			(at -0.2667 0)
			(size 0.3048 0.381)
			(layers "F.Cu" "F.Mask" "F.Paste")
			(net "P5E_PEX2_STN1_TX_DP<30>")
		)
		(pad "2" smd rect
			(at 0.2667 0)
			(size 0.3048 0.381)
			(layers "F.Cu" "F.Mask" "F.Paste")
			(net "P5E_PEX2_STN1_TX_C_DP<30>")
		)
	)
	(footprint ""
		(layer "F.Cu")
		(at 378.2949 -343.952322 90)
		(property "Reference" "C767"
			(at 0 0 90)
			(layer "F.SilkS")
			(hide yes)
			(effects
				(font
					(size 1.27 1.27)
				)
			)
		)
		(property "Value" ""
			(at 0 0 90)
			(layer "F.Fab")
			(effects
				(font
					(size 1.27 1.27)
				)
			)
		)
		(duplicate_pad_numbers_are_jumpers no)
		(fp_line
			(start 0.299974 -0.150114)
			(end 0.299974 0.150114)
			(stroke
				(width 0.1)
				(type default)
			)
			(layer "F.Fab")
		)
		(fp_line
			(start -0.299974 -0.150114)
			(end 0.299974 -0.150114)
			(stroke
				(width 0.1)
				(type default)
			)
			(layer "F.Fab")
		)
		(fp_line
			(start 0.299974 0.150114)
			(end -0.299974 0.150114)
			(stroke
				(width 0.1)
				(type default)
			)
			(layer "F.Fab")
		)
		(fp_line
			(start -0.299974 0.150114)
			(end -0.299974 -0.150114)
			(stroke
				(width 0.1)
				(type default)
			)
			(layer "F.Fab")
		)
		(pad "1" smd rect
			(at -0.2667 0 90)
			(size 0.3048 0.381)
			(layers "F.Cu" "F.Mask" "F.Paste")
			(net "P5E_PEX3_STN6_TX_DN<109>")
		)
		(pad "2" smd rect
			(at 0.2667 0 90)
			(size 0.3048 0.381)
			(layers "F.Cu" "F.Mask" "F.Paste")
			(net "P5E_PEX3_STN6_TX_C_DN<109>")
		)
	)
)
